# T6G (Grand Teton) — schematic netlist excerpt (pin names and nets, part order shuffled) for the footprints in the layout excerpt that follows; sources: Cadence DE-HDL packaged netlist, KiCad conversion of 04192023_DAF0TMB3IC0_F0TG_MB_C_brd_V02_OCP.brd

R8306  Q_RES  0 5% CHIP  pkg 0402LF  page 28 : A = CLK_100M_CPU0_CLK13_R_DN ; B = CLK_100M_CPU0_CLK13_DN
R2983  Q_RES  0 5% CHIP  pkg 0402LF  page 245 : A = SMB_IOEXP_3V3AUX_SDA ; B = SMB_IOEXP_3V3AUX_SDA_R1

(kicad_pcb
	(version 20260206)
	(generator "pcbnew")
	(generator_version "10.0")
	(general
		(thickness 1.6)
		(legacy_teardrops no)
	)
	(paper "A4")
	(title_block
		(title "04192023_DAF0TMB3IC0_F0TG_MB_C_brd_V02_OCP.brd")
		(comment 1 "Grand Teton / footprints 2415-2416 of 8354")
	)
	(layers
		(0 "F.Cu" signal "TOP")
		(4 "In1.Cu" signal "GND")
		(6 "In2.Cu" signal "IN1")
		(8 "In3.Cu" signal "GND1")
		(10 "In4.Cu" signal "IN2")
		(12 "In5.Cu" signal "GND2")
		(14 "In6.Cu" signal "IN3")
		(16 "In7.Cu" signal "GND3")
		(18 "In8.Cu" signal "VCC")
		(20 "In9.Cu" signal "VCC1")
		(22 "In10.Cu" signal "GND4")
		(24 "In11.Cu" signal "IN4")
		(26 "In12.Cu" signal "GND5")
		(28 "In13.Cu" signal "IN5")
		(30 "In14.Cu" signal "GND6")
		(32 "In15.Cu" signal "IN6")
		(34 "In16.Cu" signal "GND7")
		(2 "B.Cu" signal "BOTTOM")
		(9 "F.Adhes" user "F.Adhesive")
		(11 "B.Adhes" user "B.Adhesive")
		(13 "F.Paste" user "Package Geometry/Pastemask Top")
		(15 "B.Paste" user "Package Geometry/Pastemask Bottom")
		(5 "F.SilkS" user "Ref Des/Silkscreen Top")
		(7 "B.SilkS" user "Ref Des/Silkscreen Bottom")
		(1 "F.Mask" user "Board Geometry/Soldermask Top")
		(3 "B.Mask" user "Board Geometry/Soldermask Bottom")
		(17 "Dwgs.User" user "User.Drawings")
		(19 "Cmts.User" user "User.Comments")
		(21 "Eco1.User" user "User.Eco1")
		(23 "Eco2.User" user "User.Eco2")
		(25 "Edge.Cuts" user "Board Geometry/Outline")
		(27 "Margin" user)
		(31 "F.CrtYd" user "Package Geometry/Place Bound Top")
		(29 "B.CrtYd" user "Package Geometry/Place Bound Bottom")
		(35 "F.Fab" user "Ref Des/Assembly Top")
		(33 "B.Fab" user "Ref Des/Assembly Bottom")
	)
	(footprint ""
		(layer "F.Cu")
		(at 360.098594 -320.132964 90)
		(property "Reference" "R8306"
			(at 0 0 90)
			(layer "F.SilkS")
			(hide yes)
			(effects
				(font
					(size 1.27 1.27)
				)
			)
		)
		(property "Value" ""
			(at 0 0 90)
			(layer "F.Fab")
			(effects
				(font
					(size 1.27 1.27)
				)
			)
		)
		(duplicate_pad_numbers_are_jumpers no)
		(fp_line
			(start 0.7874 -0.4064)
			(end 0.7874 -0.053594)
			(stroke
				(width 0.1524)
				(type default)
			)
			(layer "F.SilkS")
		)
		(fp_line
			(start -0.7874 -0.4064)
			(end 0.7874 -0.4064)
			(stroke
				(width 0.1524)
				(type default)
			)
			(layer "F.SilkS")
		)
		(fp_line
			(start -0.7874 0.022606)
			(end -0.7874 -0.4064)
			(stroke
				(width 0.1524)
				(type default)
			)
			(layer "F.SilkS")
		)
		(fp_line
			(start 0.364236 0.4064)
			(end -0.372364 0.4064)
			(stroke
				(width 0.1524)
				(type default)
			)
			(layer "F.SilkS")
		)
		(fp_line
			(start -0.12065 -0.305054)
			(end -0.12065 -0.2794)
			(stroke
				(width 0.1)
				(type default)
			)
			(layer "F.Fab")
		)
		(fp_line
			(start -0.67945 -0.305054)
			(end -0.12065 -0.305054)
			(stroke
				(width 0.1)
				(type default)
			)
			(layer "F.Fab")
		)
		(fp_line
			(start 0.67945 -0.3048)
			(end 0.67945 0.3048)
			(stroke
				(width 0.1)
				(type default)
			)
			(layer "F.Fab")
		)
		(fp_line
			(start 0.12065 -0.3048)
			(end 0.67945 -0.3048)
			(stroke
				(width 0.1)
				(type default)
			)
			(layer "F.Fab")
		)
		(fp_line
			(start 0.12065 -0.2794)
			(end 0.12065 -0.3048)
			(stroke
				(width 0.1)
				(type default)
			)
			(layer "F.Fab")
		)
		(fp_line
			(start -0.12065 -0.2794)
			(end 0.12065 -0.2794)
			(stroke
				(width 0.1)
				(type default)
			)
			(layer "F.Fab")
		)
		(fp_line
			(start 0.120396 0.2794)
			(end -0.12065 0.2794)
			(stroke
				(width 0.1)
				(type default)
			)
			(layer "F.Fab")
		)
		(fp_line
			(start -0.12065 0.2794)
			(end -0.12065 0.3048)
			(stroke
				(width 0.1)
				(type default)
			)
			(layer "F.Fab")
		)
		(fp_line
			(start 0.67945 0.3048)
			(end 0.120396 0.3048)
			(stroke
				(width 0.1)
				(type default)
			)
			(layer "F.Fab")
		)
		(fp_line
			(start 0.120396 0.3048)
			(end 0.120396 0.2794)
			(stroke
				(width 0.1)
				(type default)
			)
			(layer "F.Fab")
		)
		(fp_line
			(start -0.12065 0.3048)
			(end -0.67945 0.3048)
			(stroke
				(width 0.1)
				(type default)
			)
			(layer "F.Fab")
		)
		(fp_line
			(start -0.67945 0.3048)
			(end -0.67945 -0.305054)
			(stroke
				(width 0.1)
				(type default)
			)
			(layer "F.Fab")
		)
		(pad "1" smd circle
			(at -0.40005 0 90)
			(size 0 0)
			(layers "F.Cu" "F.Mask" "F.Paste")
			(net "CLK_100M_CPU0_CLK13_R_DN")
		)
		(pad "2" smd circle
			(at 0.40005 0 90)
			(size 0 0)
			(layers "F.Cu" "F.Mask" "F.Paste")
			(net "CLK_100M_CPU0_CLK13_DN")
		)
	)
	(footprint ""
		(layer "F.Cu")
		(at 177.397918 -424.283632)
		(property "Reference" "R2983"
			(at 0 0 0)
			(layer "F.SilkS")
			(hide yes)
			(effects
				(font
					(size 1.27 1.27)
				)
			)
		)
		(property "Value" ""
			(at 0 0 0)
			(layer "F.Fab")
			(effects
				(font
					(size 1.27 1.27)
				)
			)
		)
		(duplicate_pad_numbers_are_jumpers no)
		(fp_line
			(start -0.7874 -0.4064)
			(end 0.7874 -0.4064)
			(stroke
				(width 0.1524)
				(type default)
			)
			(layer "F.SilkS")
		)
		(fp_line
			(start -0.7874 0.4064)
			(end -0.7874 -0.4064)
			(stroke
				(width 0.1524)
				(type default)
			)
			(layer "F.SilkS")
		)
		(fp_line
			(start 0.7874 -0.4064)
			(end 0.7874 0.4064)
			(stroke
				(width 0.1524)
				(type default)
			)
			(layer "F.SilkS")
		)
		(fp_line
			(start 0.7874 0.4064)
			(end -0.7874 0.4064)
			(stroke
				(width 0.1524)
				(type default)
			)
			(layer "F.SilkS")
		)
		(fp_line
			(start -0.67945 -0.305054)
			(end -0.12065 -0.305054)
			(stroke
				(width 0.1)
				(type default)
			)
			(layer "F.Fab")
		)
		(fp_line
			(start -0.67945 0.3048)
			(end -0.67945 -0.305054)
			(stroke
				(width 0.1)
				(type default)
			)
			(layer "F.Fab")
		)
		(fp_line
			(start -0.12065 -0.305054)
			(end -0.12065 -0.2794)
			(stroke
				(width 0.1)
				(type default)
			)
			(layer "F.Fab")
		)
		(fp_line
			(start -0.12065 -0.2794)
			(end 0.12065 -0.2794)
			(stroke
				(width 0.1)
				(type default)
			)
			(layer "F.Fab")
		)
		(fp_line
			(start -0.12065 0.2794)
			(end -0.12065 0.3048)
			(stroke
				(width 0.1)
				(type default)
			)
			(layer "F.Fab")
		)
		(fp_line
			(start -0.12065 0.3048)
			(end -0.67945 0.3048)
			(stroke
				(width 0.1)
				(type default)
			)
			(layer "F.Fab")
		)
		(fp_line
			(start 0.120396 0.2794)
			(end -0.12065 0.2794)
			(stroke
				(width 0.1)
				(type default)
			)
			(layer "F.Fab")
		)
		(fp_line
			(start 0.120396 0.3048)
			(end 0.120396 0.2794)
			(stroke
				(width 0.1)
				(type default)
			)
			(layer "F.Fab")
		)
		(fp_line
			(start 0.12065 -0.3048)
			(end 0.67945 -0.3048)
			(stroke
				(width 0.1)
				(type default)
			)
			(layer "F.Fab")
		)
		(fp_line
			(start 0.12065 -0.2794)
			(end 0.12065 -0.3048)
			(stroke
				(width 0.1)
				(type default)
			)
			(layer "F.Fab")
		)
		(fp_line
			(start 0.67945 -0.3048)
			(end 0.67945 0.3048)
			(stroke
				(width 0.1)
				(type default)
			)
			(layer "F.Fab")
		)
		(fp_line
			(start 0.67945 0.3048)
			(end 0.120396 0.3048)
			(stroke
				(width 0.1)
				(type default)
			)
			(layer "F.Fab")
		)
		(pad "1" smd circle
			(at -0.40005 0)
			(size 0 0)
			(layers "F.Cu" "F.Mask" "F.Paste")
			(net "SMB_IOEXP_3V3AUX_SDA")
		)
		(pad "2" smd circle
			(at 0.40005 0)
			(size 0 0)
			(layers "F.Cu" "F.Mask" "F.Paste")
			(net "SMB_IOEXP_3V3AUX_SDA_R1")
		)
	)
)
